# T6G (Grand Teton) — schematic netlist excerpt (pin names and nets, part order shuffled) for the footprints in the layout excerpt that follows; sources: Cadence DE-HDL packaged netlist, KiCad conversion of 04192023_DAF0TMB3IC0_F0TG_MB_C_brd_V02_OCP.brd

PR6812  Q_RES  1K 1% CHIP  pkg 0402LF  page 364 : A = P3V3_AUX ; B = TP_P0V9_RETIMER_CPU1_VRHOT
C2477  Q_CAP  22UF 4V 20% X6S  pkg C0402  page 74 : A = PVDDIO_P1 ; B = GND

(kicad_pcb
	(version 20260206)
	(generator "pcbnew")
	(generator_version "10.0")
	(general
		(thickness 1.6)
		(legacy_teardrops no)
	)
	(paper "A4")
	(title_block
		(title "04192023_DAF0TMB3IC0_F0TG_MB_C_brd_V02_OCP.brd")
		(comment 1 "Grand Teton / footprints 5657-5658 of 8354")
	)
	(layers
		(0 "F.Cu" signal "TOP")
		(4 "In1.Cu" signal "GND")
		(6 "In2.Cu" signal "IN1")
		(8 "In3.Cu" signal "GND1")
		(10 "In4.Cu" signal "IN2")
		(12 "In5.Cu" signal "GND2")
		(14 "In6.Cu" signal "IN3")
		(16 "In7.Cu" signal "GND3")
		(18 "In8.Cu" signal "VCC")
		(20 "In9.Cu" signal "VCC1")
		(22 "In10.Cu" signal "GND4")
		(24 "In11.Cu" signal "IN4")
		(26 "In12.Cu" signal "GND5")
		(28 "In13.Cu" signal "IN5")
		(30 "In14.Cu" signal "GND6")
		(32 "In15.Cu" signal "IN6")
		(34 "In16.Cu" signal "GND7")
		(2 "B.Cu" signal "BOTTOM")
		(9 "F.Adhes" user "F.Adhesive")
		(11 "B.Adhes" user "B.Adhesive")
		(13 "F.Paste" user "Package Geometry/Pastemask Top")
		(15 "B.Paste" user "Package Geometry/Pastemask Bottom")
		(5 "F.SilkS" user "Ref Des/Silkscreen Top")
		(7 "B.SilkS" user "Ref Des/Silkscreen Bottom")
		(1 "F.Mask" user "Board Geometry/Soldermask Top")
		(3 "B.Mask" user "Board Geometry/Soldermask Bottom")
		(17 "Dwgs.User" user "User.Drawings")
		(19 "Cmts.User" user "User.Comments")
		(21 "Eco1.User" user "User.Eco1")
		(23 "Eco2.User" user "User.Eco2")
		(25 "Edge.Cuts" user "Board Geometry/Outline")
		(27 "Margin" user)
		(31 "F.CrtYd" user "Package Geometry/Place Bound Top")
		(29 "B.CrtYd" user "Package Geometry/Place Bound Bottom")
		(35 "F.Fab" user "Ref Des/Assembly Top")
		(33 "B.Fab" user "Ref Des/Assembly Bottom")
	)
	(footprint ""
		(layer "B.Cu")
		(at 20.743418 -409.04287 90)
		(property "Reference" "PR6812"
			(at 0 0 90)
			(layer "B.SilkS")
			(hide yes)
			(effects
				(font
					(size 1.27 1.27)
				)
				(justify mirror)
			)
		)
		(property "Value" ""
			(at 0 0 90)
			(layer "B.Fab")
			(effects
				(font
					(size 1.27 1.27)
				)
				(justify mirror)
			)
		)
		(duplicate_pad_numbers_are_jumpers no)
		(fp_line
			(start 0.7874 -0.4064)
			(end -0.7874 -0.4064)
			(stroke
				(width 0.1524)
				(type default)
			)
			(layer "B.SilkS")
		)
		(fp_line
			(start -0.7874 -0.4064)
			(end -0.7874 0.4064)
			(stroke
				(width 0.1524)
				(type default)
			)
			(layer "B.SilkS")
		)
		(fp_line
			(start 0.7874 0.4064)
			(end 0.7874 -0.4064)
			(stroke
				(width 0.1524)
				(type default)
			)
			(layer "B.SilkS")
		)
		(fp_line
			(start -0.7874 0.4064)
			(end 0.7874 0.4064)
			(stroke
				(width 0.1524)
				(type default)
			)
			(layer "B.SilkS")
		)
		(fp_line
			(start 0.67945 -0.305054)
			(end 0.12065 -0.305054)
			(stroke
				(width 0.1)
				(type default)
			)
			(layer "B.Fab")
		)
		(fp_line
			(start 0.12065 -0.305054)
			(end 0.12065 -0.2794)
			(stroke
				(width 0.1)
				(type default)
			)
			(layer "B.Fab")
		)
		(fp_line
			(start -0.12065 -0.3048)
			(end -0.67945 -0.3048)
			(stroke
				(width 0.1)
				(type default)
			)
			(layer "B.Fab")
		)
		(fp_line
			(start -0.67945 -0.3048)
			(end -0.67945 0.3048)
			(stroke
				(width 0.1)
				(type default)
			)
			(layer "B.Fab")
		)
		(fp_line
			(start 0.12065 -0.2794)
			(end -0.12065 -0.2794)
			(stroke
				(width 0.1)
				(type default)
			)
			(layer "B.Fab")
		)
		(fp_line
			(start -0.12065 -0.2794)
			(end -0.12065 -0.3048)
			(stroke
				(width 0.1)
				(type default)
			)
			(layer "B.Fab")
		)
		(fp_line
			(start 0.12065 0.2794)
			(end 0.12065 0.3048)
			(stroke
				(width 0.1)
				(type default)
			)
			(layer "B.Fab")
		)
		(fp_line
			(start -0.120396 0.2794)
			(end 0.12065 0.2794)
			(stroke
				(width 0.1)
				(type default)
			)
			(layer "B.Fab")
		)
		(fp_line
			(start 0.67945 0.3048)
			(end 0.67945 -0.305054)
			(stroke
				(width 0.1)
				(type default)
			)
			(layer "B.Fab")
		)
		(fp_line
			(start 0.12065 0.3048)
			(end 0.67945 0.3048)
			(stroke
				(width 0.1)
				(type default)
			)
			(layer "B.Fab")
		)
		(fp_line
			(start -0.120396 0.3048)
			(end -0.120396 0.2794)
			(stroke
				(width 0.1)
				(type default)
			)
			(layer "B.Fab")
		)
		(fp_line
			(start -0.67945 0.3048)
			(end -0.120396 0.3048)
			(stroke
				(width 0.1)
				(type default)
			)
			(layer "B.Fab")
		)
		(pad "1" smd circle
			(at 0.40005 0 270)
			(size 0 0)
			(layers "B.Cu" "B.Mask" "B.Paste")
			(net "P3V3_AUX")
		)
		(pad "2" smd circle
			(at -0.40005 0 270)
			(size 0 0)
			(layers "B.Cu" "B.Mask" "B.Paste")
			(net "TP_P0V9_RETIMER_CPU1_VRHOT")
		)
	)
	(footprint ""
		(layer "B.Cu")
		(at 108.355892 -259.845302 180)
		(property "Reference" "C2477"
			(at 0 0 0)
			(layer "B.SilkS")
			(hide yes)
			(effects
				(font
					(size 1.27 1.27)
				)
				(justify mirror)
			)
		)
		(property "Value" ""
			(at 0 0 0)
			(layer "B.Fab")
			(effects
				(font
					(size 1.27 1.27)
				)
				(justify mirror)
			)
		)
		(duplicate_pad_numbers_are_jumpers no)
		(fp_line
			(start 0.7874 0.4064)
			(end 0.7874 -0.4064)
			(stroke
				(width 0.1524)
				(type default)
			)
			(layer "B.SilkS")
		)
		(fp_line
			(start 0.7874 -0.4064)
			(end -0.7874 -0.4064)
			(stroke
				(width 0.1524)
				(type default)
			)
			(layer "B.SilkS")
		)
		(fp_line
			(start -0.7874 0.4064)
			(end 0.7874 0.4064)
			(stroke
				(width 0.1524)
				(type default)
			)
			(layer "B.SilkS")
		)
		(fp_line
			(start -0.7874 -0.4064)
			(end -0.7874 0.4064)
			(stroke
				(width 0.1524)
				(type default)
			)
			(layer "B.SilkS")
		)
		(fp_line
			(start 0.67945 0.3048)
			(end 0.67945 -0.305054)
			(stroke
				(width 0.1)
				(type default)
			)
			(layer "B.Fab")
		)
		(fp_line
			(start 0.67945 -0.305054)
			(end 0.12065 -0.305054)
			(stroke
				(width 0.1)
				(type default)
			)
			(layer "B.Fab")
		)
		(fp_line
			(start 0.12065 0.3048)
			(end 0.67945 0.3048)
			(stroke
				(width 0.1)
				(type default)
			)
			(layer "B.Fab")
		)
		(fp_line
			(start 0.12065 0.2794)
			(end 0.12065 0.3048)
			(stroke
				(width 0.1)
				(type default)
			)
			(layer "B.Fab")
		)
		(fp_line
			(start 0.12065 -0.2794)
			(end -0.12065 -0.2794)
			(stroke
				(width 0.1)
				(type default)
			)
			(layer "B.Fab")
		)
		(fp_line
			(start 0.12065 -0.305054)
			(end 0.12065 -0.2794)
			(stroke
				(width 0.1)
				(type default)
			)
			(layer "B.Fab")
		)
		(fp_line
			(start -0.120396 0.3048)
			(end -0.120396 0.2794)
			(stroke
				(width 0.1)
				(type default)
			)
			(layer "B.Fab")
		)
		(fp_line
			(start -0.120396 0.2794)
			(end 0.12065 0.2794)
			(stroke
				(width 0.1)
				(type default)
			)
			(layer "B.Fab")
		)
		(fp_line
			(start -0.12065 -0.2794)
			(end -0.12065 -0.3048)
			(stroke
				(width 0.1)
				(type default)
			)
			(layer "B.Fab")
		)
		(fp_line
			(start -0.12065 -0.3048)
			(end -0.67945 -0.3048)
			(stroke
				(width 0.1)
				(type default)
			)
			(layer "B.Fab")
		)
		(fp_line
			(start -0.67945 0.3048)
			(end -0.120396 0.3048)
			(stroke
				(width 0.1)
				(type default)
			)
			(layer "B.Fab")
		)
		(fp_line
			(start -0.67945 -0.3048)
			(end -0.67945 0.3048)
			(stroke
				(width 0.1)
				(type default)
			)
			(layer "B.Fab")
		)
		(pad "1" smd circle
			(at 0.40005 0)
			(size 0 0)
			(layers "B.Cu" "B.Mask" "B.Paste")
			(net "PVDDIO_P1")
		)
		(pad "2" smd circle
			(at -0.40005 0)
			(size 0 0)
			(layers "B.Cu" "B.Mask" "B.Paste")
			(net "GND")
		)
	)
)
